# T6G (Grand Teton) — schematic netlist excerpt (pin names and nets, part order shuffled) for the footprints in the layout excerpt that follows; sources: Cadence DE-HDL packaged netlist, KiCad conversion of 04192023_DAF0TMB3IC0_F0TG_MB_C_brd_V02_OCP.brd

R3652  Q_RES  0 5% CHIP  pkg 0402LF  page 234 : A = USB2_P0_R_DN ; B = USB2_HOST_BMC_B_DN
R6275  Q_RES  0 5% CHIP  pkg 0402LF  page 179 : A = USB_HUB2_TI_VDD33_MRP_PRT_CTL4_GANGPWR ; B = P3V3_AUX_CPU0_USB2_AVDD33

(kicad_pcb
	(version 20260206)
	(generator "pcbnew")
	(generator_version "10.0")
	(general
		(thickness 1.6)
		(legacy_teardrops no)
	)
	(paper "A4")
	(title_block
		(title "04192023_DAF0TMB3IC0_F0TG_MB_C_brd_V02_OCP.brd")
		(comment 1 "Grand Teton / footprints 1098-1099 of 8354")
	)
	(layers
		(0 "F.Cu" signal "TOP")
		(4 "In1.Cu" signal "GND")
		(6 "In2.Cu" signal "IN1")
		(8 "In3.Cu" signal "GND1")
		(10 "In4.Cu" signal "IN2")
		(12 "In5.Cu" signal "GND2")
		(14 "In6.Cu" signal "IN3")
		(16 "In7.Cu" signal "GND3")
		(18 "In8.Cu" signal "VCC")
		(20 "In9.Cu" signal "VCC1")
		(22 "In10.Cu" signal "GND4")
		(24 "In11.Cu" signal "IN4")
		(26 "In12.Cu" signal "GND5")
		(28 "In13.Cu" signal "IN5")
		(30 "In14.Cu" signal "GND6")
		(32 "In15.Cu" signal "IN6")
		(34 "In16.Cu" signal "GND7")
		(2 "B.Cu" signal "BOTTOM")
		(9 "F.Adhes" user "F.Adhesive")
		(11 "B.Adhes" user "B.Adhesive")
		(13 "F.Paste" user "Package Geometry/Pastemask Top")
		(15 "B.Paste" user "Package Geometry/Pastemask Bottom")
		(5 "F.SilkS" user "Ref Des/Silkscreen Top")
		(7 "B.SilkS" user "Ref Des/Silkscreen Bottom")
		(1 "F.Mask" user "Board Geometry/Soldermask Top")
		(3 "B.Mask" user "Board Geometry/Soldermask Bottom")
		(17 "Dwgs.User" user "User.Drawings")
		(19 "Cmts.User" user "User.Comments")
		(21 "Eco1.User" user "User.Eco1")
		(23 "Eco2.User" user "User.Eco2")
		(25 "Edge.Cuts" user "Board Geometry/Outline")
		(27 "Margin" user)
		(31 "F.CrtYd" user "Package Geometry/Place Bound Top")
		(29 "B.CrtYd" user "Package Geometry/Place Bound Bottom")
		(35 "F.Fab" user "Ref Des/Assembly Top")
		(33 "B.Fab" user "Ref Des/Assembly Bottom")
	)
	(footprint ""
		(layer "F.Cu")
		(at 16.645382 -104.76611 90)
		(property "Reference" "R3652"
			(at 0 0 90)
			(layer "F.SilkS")
			(hide yes)
			(effects
				(font
					(size 1.27 1.27)
				)
			)
		)
		(property "Value" ""
			(at 0 0 90)
			(layer "F.Fab")
			(effects
				(font
					(size 1.27 1.27)
				)
			)
		)
		(duplicate_pad_numbers_are_jumpers no)
		(fp_line
			(start 0.7874 -0.4064)
			(end 0.7874 0.4064)
			(stroke
				(width 0.1524)
				(type default)
			)
			(layer "F.SilkS")
		)
		(fp_line
			(start -0.7874 -0.4064)
			(end 0.7874 -0.4064)
			(stroke
				(width 0.1524)
				(type default)
			)
			(layer "F.SilkS")
		)
		(fp_line
			(start 0.7874 0.4064)
			(end -0.7874 0.4064)
			(stroke
				(width 0.1524)
				(type default)
			)
			(layer "F.SilkS")
		)
		(fp_line
			(start -0.7874 0.4064)
			(end -0.7874 -0.4064)
			(stroke
				(width 0.1524)
				(type default)
			)
			(layer "F.SilkS")
		)
		(fp_line
			(start -0.12065 -0.305054)
			(end -0.12065 -0.2794)
			(stroke
				(width 0.1)
				(type default)
			)
			(layer "F.Fab")
		)
		(fp_line
			(start -0.67945 -0.305054)
			(end -0.12065 -0.305054)
			(stroke
				(width 0.1)
				(type default)
			)
			(layer "F.Fab")
		)
		(fp_line
			(start 0.67945 -0.3048)
			(end 0.67945 0.3048)
			(stroke
				(width 0.1)
				(type default)
			)
			(layer "F.Fab")
		)
		(fp_line
			(start 0.12065 -0.3048)
			(end 0.67945 -0.3048)
			(stroke
				(width 0.1)
				(type default)
			)
			(layer "F.Fab")
		)
		(fp_line
			(start 0.12065 -0.2794)
			(end 0.12065 -0.3048)
			(stroke
				(width 0.1)
				(type default)
			)
			(layer "F.Fab")
		)
		(fp_line
			(start -0.12065 -0.2794)
			(end 0.12065 -0.2794)
			(stroke
				(width 0.1)
				(type default)
			)
			(layer "F.Fab")
		)
		(fp_line
			(start 0.120396 0.2794)
			(end -0.12065 0.2794)
			(stroke
				(width 0.1)
				(type default)
			)
			(layer "F.Fab")
		)
		(fp_line
			(start -0.12065 0.2794)
			(end -0.12065 0.3048)
			(stroke
				(width 0.1)
				(type default)
			)
			(layer "F.Fab")
		)
		(fp_line
			(start 0.67945 0.3048)
			(end 0.120396 0.3048)
			(stroke
				(width 0.1)
				(type default)
			)
			(layer "F.Fab")
		)
		(fp_line
			(start 0.120396 0.3048)
			(end 0.120396 0.2794)
			(stroke
				(width 0.1)
				(type default)
			)
			(layer "F.Fab")
		)
		(fp_line
			(start -0.12065 0.3048)
			(end -0.67945 0.3048)
			(stroke
				(width 0.1)
				(type default)
			)
			(layer "F.Fab")
		)
		(fp_line
			(start -0.67945 0.3048)
			(end -0.67945 -0.305054)
			(stroke
				(width 0.1)
				(type default)
			)
			(layer "F.Fab")
		)
		(pad "1" smd rect
			(at -0.40005 0 270)
			(size 0.4572 0.508)
			(layers "F.Cu" "F.Mask" "F.Paste")
			(net "USB2_P0_R_DN")
		)
		(pad "2" smd rect
			(at 0.40005 0 270)
			(size 0.4572 0.508)
			(layers "F.Cu" "F.Mask" "F.Paste")
			(net "USB2_HOST_BMC_B_DN")
		)
	)
	(footprint ""
		(layer "F.Cu")
		(at 124.459238 -41.17975 90)
		(property "Reference" "R6275"
			(at 0 0 90)
			(layer "F.SilkS")
			(hide yes)
			(effects
				(font
					(size 1.27 1.27)
				)
			)
		)
		(property "Value" ""
			(at 0 0 90)
			(layer "F.Fab")
			(effects
				(font
					(size 1.27 1.27)
				)
			)
		)
		(duplicate_pad_numbers_are_jumpers no)
		(fp_line
			(start 0.7874 -0.4064)
			(end 0.7874 0.4064)
			(stroke
				(width 0.1524)
				(type default)
			)
			(layer "F.SilkS")
		)
		(fp_line
			(start -0.7874 -0.4064)
			(end 0.7874 -0.4064)
			(stroke
				(width 0.1524)
				(type default)
			)
			(layer "F.SilkS")
		)
		(fp_line
			(start 0.7874 0.4064)
			(end -0.7874 0.4064)
			(stroke
				(width 0.1524)
				(type default)
			)
			(layer "F.SilkS")
		)
		(fp_line
			(start -0.7874 0.4064)
			(end -0.7874 -0.4064)
			(stroke
				(width 0.1524)
				(type default)
			)
			(layer "F.SilkS")
		)
		(fp_line
			(start -0.12065 -0.305054)
			(end -0.12065 -0.2794)
			(stroke
				(width 0.1)
				(type default)
			)
			(layer "F.Fab")
		)
		(fp_line
			(start -0.67945 -0.305054)
			(end -0.12065 -0.305054)
			(stroke
				(width 0.1)
				(type default)
			)
			(layer "F.Fab")
		)
		(fp_line
			(start 0.67945 -0.3048)
			(end 0.67945 0.3048)
			(stroke
				(width 0.1)
				(type default)
			)
			(layer "F.Fab")
		)
		(fp_line
			(start 0.12065 -0.3048)
			(end 0.67945 -0.3048)
			(stroke
				(width 0.1)
				(type default)
			)
			(layer "F.Fab")
		)
		(fp_line
			(start 0.12065 -0.2794)
			(end 0.12065 -0.3048)
			(stroke
				(width 0.1)
				(type default)
			)
			(layer "F.Fab")
		)
		(fp_line
			(start -0.12065 -0.2794)
			(end 0.12065 -0.2794)
			(stroke
				(width 0.1)
				(type default)
			)
			(layer "F.Fab")
		)
		(fp_line
			(start 0.120396 0.2794)
			(end -0.12065 0.2794)
			(stroke
				(width 0.1)
				(type default)
			)
			(layer "F.Fab")
		)
		(fp_line
			(start -0.12065 0.2794)
			(end -0.12065 0.3048)
			(stroke
				(width 0.1)
				(type default)
			)
			(layer "F.Fab")
		)
		(fp_line
			(start 0.67945 0.3048)
			(end 0.120396 0.3048)
			(stroke
				(width 0.1)
				(type default)
			)
			(layer "F.Fab")
		)
		(fp_line
			(start 0.120396 0.3048)
			(end 0.120396 0.2794)
			(stroke
				(width 0.1)
				(type default)
			)
			(layer "F.Fab")
		)
		(fp_line
			(start -0.12065 0.3048)
			(end -0.67945 0.3048)
			(stroke
				(width 0.1)
				(type default)
			)
			(layer "F.Fab")
		)
		(fp_line
			(start -0.67945 0.3048)
			(end -0.67945 -0.305054)
			(stroke
				(width 0.1)
				(type default)
			)
			(layer "F.Fab")
		)
		(pad "1" smd circle
			(at -0.40005 0 90)
			(size 0 0)
			(layers "F.Cu" "F.Mask" "F.Paste")
			(net "USB_HUB2_TI_VDD33_MRP_PRT_CTL4_GANGPWR")
		)
		(pad "2" smd circle
			(at 0.40005 0 90)
			(size 0 0)
			(layers "F.Cu" "F.Mask" "F.Paste")
			(net "P3V3_AUX_CPU0_USB2_AVDD33")
		)
	)
)
